# S9S_MB_2U (Grand Teton) — schematic netlist excerpt (pin names and nets, part order shuffled) for the footprints in the layout excerpt that follows; sources: Cadence DE-HDL packaged netlist, KiCad conversion of 03242023_DA0F0TMBIJ0_F0T_Motherboard_J_brd_V01_OCP.brd

R4579  Q_RES  10K 1% CHIP  pkg 0402LF  page 195 : A = P3V3_AUX ; B = FAB_BMC_REV_ID0
R3267  Q_RES  68K 1% EMPTY  pkg 0402LF  page 166 : A = FM_P2E_FGB ; B = GND

(kicad_pcb
	(version 20260206)
	(generator "pcbnew")
	(generator_version "10.0")
	(general
		(thickness 1.6)
		(legacy_teardrops no)
	)
	(paper "A4")
	(title_block
		(title "03242023_DA0F0TMBIJ0_F0T_Motherboard_J_brd_V01_OCP.brd")
		(comment 1 "Grand Teton / footprints 1371-1372 of 6105")
	)
	(layers
		(0 "F.Cu" signal "TOP")
		(4 "In1.Cu" signal "GND")
		(6 "In2.Cu" signal "IN1")
		(8 "In3.Cu" signal "GND1")
		(10 "In4.Cu" signal "IN2")
		(12 "In5.Cu" signal "GND2")
		(14 "In6.Cu" signal "IN3")
		(16 "In7.Cu" signal "GND3")
		(18 "In8.Cu" signal "VCC")
		(20 "In9.Cu" signal "VCC1")
		(22 "In10.Cu" signal "GND4")
		(24 "In11.Cu" signal "IN4")
		(26 "In12.Cu" signal "GND5")
		(28 "In13.Cu" signal "IN5")
		(30 "In14.Cu" signal "GND6")
		(32 "In15.Cu" signal "IN6")
		(34 "In16.Cu" signal "GND7")
		(2 "B.Cu" signal "BOTTOM")
		(9 "F.Adhes" user "F.Adhesive")
		(11 "B.Adhes" user "B.Adhesive")
		(13 "F.Paste" user "Package Geometry/Pastemask Top")
		(15 "B.Paste" user "Package Geometry/Pastemask Bottom")
		(5 "F.SilkS" user "Ref Des/Silkscreen Top")
		(7 "B.SilkS" user "Ref Des/Silkscreen Bottom")
		(1 "F.Mask" user "Board Geometry/Soldermask Top")
		(3 "B.Mask" user "Board Geometry/Soldermask Bottom")
		(17 "Dwgs.User" user "User.Drawings")
		(19 "Cmts.User" user "User.Comments")
		(21 "Eco1.User" user "User.Eco1")
		(23 "Eco2.User" user "User.Eco2")
		(25 "Edge.Cuts" user "Board Geometry/Outline")
		(27 "Margin" user)
		(31 "F.CrtYd" user "Package Geometry/Place Bound Top")
		(29 "B.CrtYd" user "Package Geometry/Place Bound Bottom")
		(35 "F.Fab" user "Ref Des/Assembly Top")
		(33 "B.Fab" user "Ref Des/Assembly Bottom")
	)
	(footprint ""
		(layer "F.Cu")
		(at 27.628596 -392.326876)
		(property "Reference" "R3267"
			(at 0 0 0)
			(layer "F.SilkS")
			(hide yes)
			(effects
				(font
					(size 1.27 1.27)
				)
			)
		)
		(property "Value" ""
			(at 0 0 0)
			(layer "F.Fab")
			(effects
				(font
					(size 1.27 1.27)
				)
			)
		)
		(duplicate_pad_numbers_are_jumpers no)
		(fp_line
			(start -0.7874 -0.4064)
			(end 0.7874 -0.4064)
			(stroke
				(width 0.1524)
				(type default)
			)
			(layer "F.SilkS")
		)
		(fp_line
			(start -0.7874 0.4064)
			(end -0.7874 -0.4064)
			(stroke
				(width 0.1524)
				(type default)
			)
			(layer "F.SilkS")
		)
		(fp_line
			(start 0.7874 -0.4064)
			(end 0.7874 0.4064)
			(stroke
				(width 0.1524)
				(type default)
			)
			(layer "F.SilkS")
		)
		(fp_line
			(start 0.7874 0.4064)
			(end -0.7874 0.4064)
			(stroke
				(width 0.1524)
				(type default)
			)
			(layer "F.SilkS")
		)
		(fp_line
			(start -0.67945 -0.305054)
			(end -0.12065 -0.305054)
			(stroke
				(width 0.1)
				(type default)
			)
			(layer "F.Fab")
		)
		(fp_line
			(start -0.67945 0.3048)
			(end -0.67945 -0.305054)
			(stroke
				(width 0.1)
				(type default)
			)
			(layer "F.Fab")
		)
		(fp_line
			(start -0.12065 -0.305054)
			(end -0.12065 -0.2794)
			(stroke
				(width 0.1)
				(type default)
			)
			(layer "F.Fab")
		)
		(fp_line
			(start -0.12065 -0.2794)
			(end 0.12065 -0.2794)
			(stroke
				(width 0.1)
				(type default)
			)
			(layer "F.Fab")
		)
		(fp_line
			(start -0.12065 0.2794)
			(end -0.12065 0.3048)
			(stroke
				(width 0.1)
				(type default)
			)
			(layer "F.Fab")
		)
		(fp_line
			(start -0.12065 0.3048)
			(end -0.67945 0.3048)
			(stroke
				(width 0.1)
				(type default)
			)
			(layer "F.Fab")
		)
		(fp_line
			(start 0.120396 0.2794)
			(end -0.12065 0.2794)
			(stroke
				(width 0.1)
				(type default)
			)
			(layer "F.Fab")
		)
		(fp_line
			(start 0.120396 0.3048)
			(end 0.120396 0.2794)
			(stroke
				(width 0.1)
				(type default)
			)
			(layer "F.Fab")
		)
		(fp_line
			(start 0.12065 -0.3048)
			(end 0.67945 -0.3048)
			(stroke
				(width 0.1)
				(type default)
			)
			(layer "F.Fab")
		)
		(fp_line
			(start 0.12065 -0.2794)
			(end 0.12065 -0.3048)
			(stroke
				(width 0.1)
				(type default)
			)
			(layer "F.Fab")
		)
		(fp_line
			(start 0.67945 -0.3048)
			(end 0.67945 0.3048)
			(stroke
				(width 0.1)
				(type default)
			)
			(layer "F.Fab")
		)
		(fp_line
			(start 0.67945 0.3048)
			(end 0.120396 0.3048)
			(stroke
				(width 0.1)
				(type default)
			)
			(layer "F.Fab")
		)
		(pad "1" smd circle
			(at -0.40005 0)
			(size 0 0)
			(layers "F.Cu" "F.Mask" "F.Paste")
			(net "FM_P2E_FGB")
		)
		(pad "2" smd circle
			(at 0.40005 0)
			(size 0 0)
			(layers "F.Cu" "F.Mask" "F.Paste")
			(net "GND")
		)
	)
	(footprint ""
		(layer "F.Cu")
		(at 180.4924 -93.538548 90)
		(property "Reference" "R4579"
			(at 0 0 90)
			(layer "F.SilkS")
			(hide yes)
			(effects
				(font
					(size 1.27 1.27)
				)
			)
		)
		(property "Value" ""
			(at 0 0 90)
			(layer "F.Fab")
			(effects
				(font
					(size 1.27 1.27)
				)
			)
		)
		(duplicate_pad_numbers_are_jumpers no)
		(fp_line
			(start 0.7874 -0.4064)
			(end 0.7874 0.4064)
			(stroke
				(width 0.1524)
				(type default)
			)
			(layer "F.SilkS")
		)
		(fp_line
			(start -0.7874 -0.4064)
			(end 0.7874 -0.4064)
			(stroke
				(width 0.1524)
				(type default)
			)
			(layer "F.SilkS")
		)
		(fp_line
			(start 0.7874 0.4064)
			(end -0.7874 0.4064)
			(stroke
				(width 0.1524)
				(type default)
			)
			(layer "F.SilkS")
		)
		(fp_line
			(start -0.7874 0.4064)
			(end -0.7874 -0.4064)
			(stroke
				(width 0.1524)
				(type default)
			)
			(layer "F.SilkS")
		)
		(fp_line
			(start -0.12065 -0.305054)
			(end -0.12065 -0.2794)
			(stroke
				(width 0.1)
				(type default)
			)
			(layer "F.Fab")
		)
		(fp_line
			(start -0.67945 -0.305054)
			(end -0.12065 -0.305054)
			(stroke
				(width 0.1)
				(type default)
			)
			(layer "F.Fab")
		)
		(fp_line
			(start 0.67945 -0.3048)
			(end 0.67945 0.3048)
			(stroke
				(width 0.1)
				(type default)
			)
			(layer "F.Fab")
		)
		(fp_line
			(start 0.12065 -0.3048)
			(end 0.67945 -0.3048)
			(stroke
				(width 0.1)
				(type default)
			)
			(layer "F.Fab")
		)
		(fp_line
			(start 0.12065 -0.2794)
			(end 0.12065 -0.3048)
			(stroke
				(width 0.1)
				(type default)
			)
			(layer "F.Fab")
		)
		(fp_line
			(start -0.12065 -0.2794)
			(end 0.12065 -0.2794)
			(stroke
				(width 0.1)
				(type default)
			)
			(layer "F.Fab")
		)
		(fp_line
			(start 0.120396 0.2794)
			(end -0.12065 0.2794)
			(stroke
				(width 0.1)
				(type default)
			)
			(layer "F.Fab")
		)
		(fp_line
			(start -0.12065 0.2794)
			(end -0.12065 0.3048)
			(stroke
				(width 0.1)
				(type default)
			)
			(layer "F.Fab")
		)
		(fp_line
			(start 0.67945 0.3048)
			(end 0.120396 0.3048)
			(stroke
				(width 0.1)
				(type default)
			)
			(layer "F.Fab")
		)
		(fp_line
			(start 0.120396 0.3048)
			(end 0.120396 0.2794)
			(stroke
				(width 0.1)
				(type default)
			)
			(layer "F.Fab")
		)
		(fp_line
			(start -0.12065 0.3048)
			(end -0.67945 0.3048)
			(stroke
				(width 0.1)
				(type default)
			)
			(layer "F.Fab")
		)
		(fp_line
			(start -0.67945 0.3048)
			(end -0.67945 -0.305054)
			(stroke
				(width 0.1)
				(type default)
			)
			(layer "F.Fab")
		)
		(pad "1" smd rect
			(at -0.40005 0 270)
			(size 0.4572 0.508)
			(layers "F.Cu" "F.Mask" "F.Paste")
			(net "P3V3_AUX")
		)
		(pad "2" smd rect
			(at 0.40005 0 270)
			(size 0.4572 0.508)
			(layers "F.Cu" "F.Mask" "F.Paste")
			(net "FAB_BMC_REV_ID0")
		)
	)
)
